(kicad_pcb
	(version 20260206)
	(generator "pcbnew")
	(generator_version "10.0")
	(general
		(thickness 1.6)
		(legacy_teardrops no)
	)
	(paper "A4")
	(title_block
		(title "01162023_DA0F0TEBIF0_F0T_Expander_BD_F_brd_V02_OCP.brd")
		(comment 1 "Grand Teton / footprints 1412-1418 of 9728")
	)
	(layers
		(0 "F.Cu" signal "TOP")
		(4 "In1.Cu" signal "GND")
		(6 "In2.Cu" signal "VCC")
		(8 "In3.Cu" signal "VCC1")
		(10 "In4.Cu" signal "GND1")
		(12 "In5.Cu" signal "IN1")
		(14 "In6.Cu" signal "GND2")
		(16 "In7.Cu" signal "IN2")
		(18 "In8.Cu" signal "GND3")
		(20 "In9.Cu" signal "IN3")
		(22 "In10.Cu" signal "GND4")
		(24 "In11.Cu" signal "IN4")
		(26 "In12.Cu" signal "GND5")
		(28 "In13.Cu" signal "IN5")
		(30 "In14.Cu" signal "GND6")
		(32 "In15.Cu" signal "IN6")
		(34 "In16.Cu" signal "GND7")
		(2 "B.Cu" signal "BOTTOM")
		(9 "F.Adhes" user "F.Adhesive")
		(11 "B.Adhes" user "B.Adhesive")
		(13 "F.Paste" user "Package Geometry/Pastemask Top")
		(15 "B.Paste" user "Package Geometry/Pastemask Bottom")
		(5 "F.SilkS" user "Ref Des/Silkscreen Top")
		(7 "B.SilkS" user "Ref Des/Silkscreen Bottom")
		(1 "F.Mask" user "Board Geometry/Soldermask Top")
		(3 "B.Mask" user "Board Geometry/Soldermask Bottom")
		(17 "Dwgs.User" user "User.Drawings")
		(19 "Cmts.User" user "User.Comments")
		(21 "Eco1.User" user "User.Eco1")
		(23 "Eco2.User" user "User.Eco2")
		(25 "Edge.Cuts" user "Board Geometry/Outline")
		(27 "Margin" user)
		(31 "F.CrtYd" user "Package Geometry/Place Bound Top")
		(29 "B.CrtYd" user "Package Geometry/Place Bound Bottom")
		(35 "F.Fab" user "Ref Des/Assembly Top")
		(33 "B.Fab" user "Ref Des/Assembly Bottom")
	)
	(footprint ""
		(layer "F.Cu")
		(at 381.009144 -27.04973 180)
		(property "Reference" "C2776"
			(at 0 0 180)
			(layer "F.SilkS")
			(hide yes)
			(effects
				(font
					(size 1.27 1.27)
				)
			)
		)
		(property "Value" ""
			(at 0 0 180)
			(layer "F.Fab")
			(effects
				(font
					(size 1.27 1.27)
				)
			)
		)
		(duplicate_pad_numbers_are_jumpers no)
		(fp_line
			(start 0.7874 0.4064)
			(end -0.7874 0.4064)
			(stroke
				(width 0.1524)
				(type default)
			)
			(layer "F.SilkS")
		)
		(fp_line
			(start 0.7874 -0.4064)
			(end 0.7874 0.4064)
			(stroke
				(width 0.1524)
				(type default)
			)
			(layer "F.SilkS")
		)
		(fp_line
			(start -0.7874 0.4064)
			(end -0.7874 -0.4064)
			(stroke
				(width 0.1524)
				(type default)
			)
			(layer "F.SilkS")
		)
		(fp_line
			(start -0.7874 -0.4064)
			(end 0.7874 -0.4064)
			(stroke
				(width 0.1524)
				(type default)
			)
			(layer "F.SilkS")
		)
		(fp_line
			(start 0.67945 0.3048)
			(end 0.120396 0.3048)
			(stroke
				(width 0.1)
				(type default)
			)
			(layer "F.Fab")
		)
		(fp_line
			(start 0.67945 -0.3048)
			(end 0.67945 0.3048)
			(stroke
				(width 0.1)
				(type default)
			)
			(layer "F.Fab")
		)
		(fp_line
			(start 0.12065 -0.2794)
			(end 0.12065 -0.3048)
			(stroke
				(width 0.1)
				(type default)
			)
			(layer "F.Fab")
		)
		(fp_line
			(start 0.12065 -0.3048)
			(end 0.67945 -0.3048)
			(stroke
				(width 0.1)
				(type default)
			)
			(layer "F.Fab")
		)
		(fp_line
			(start 0.120396 0.3048)
			(end 0.120396 0.2794)
			(stroke
				(width 0.1)
				(type default)
			)
			(layer "F.Fab")
		)
		(fp_line
			(start 0.120396 0.2794)
			(end -0.12065 0.2794)
			(stroke
				(width 0.1)
				(type default)
			)
			(layer "F.Fab")
		)
		(fp_line
			(start -0.12065 0.3048)
			(end -0.67945 0.3048)
			(stroke
				(width 0.1)
				(type default)
			)
			(layer "F.Fab")
		)
		(fp_line
			(start -0.12065 0.2794)
			(end -0.12065 0.3048)
			(stroke
				(width 0.1)
				(type default)
			)
			(layer "F.Fab")
		)
		(fp_line
			(start -0.12065 -0.2794)
			(end 0.12065 -0.2794)
			(stroke
				(width 0.1)
				(type default)
			)
			(layer "F.Fab")
		)
		(fp_line
			(start -0.12065 -0.305054)
			(end -0.12065 -0.2794)
			(stroke
				(width 0.1)
				(type default)
			)
			(layer "F.Fab")
		)
		(fp_line
			(start -0.67945 0.3048)
			(end -0.67945 -0.305054)
			(stroke
				(width 0.1)
				(type default)
			)
			(layer "F.Fab")
		)
		(fp_line
			(start -0.67945 -0.305054)
			(end -0.12065 -0.305054)
			(stroke
				(width 0.1)
				(type default)
			)
			(layer "F.Fab")
		)
		(pad "1" smd circle
			(at -0.40005 0 180)
			(size 0 0)
			(layers "F.Cu" "F.Mask" "F.Paste")
			(net "PRSNT_SSD13_R_N")
		)
		(pad "2" smd circle
			(at 0.40005 0 180)
			(size 0 0)
			(layers "F.Cu" "F.Mask" "F.Paste")
			(net "GND")
		)
	)
	(footprint ""
		(layer "F.Cu")
		(at 236.895894 -49.930558 -90)
		(property "Reference" "PC568"
			(at 0 0 270)
			(layer "F.SilkS")
			(hide yes)
			(effects
				(font
					(size 1.27 1.27)
				)
			)
		)
		(property "Value" ""
			(at 0 0 270)
			(layer "F.Fab")
			(effects
				(font
					(size 1.27 1.27)
				)
			)
		)
		(duplicate_pad_numbers_are_jumpers no)
		(fp_line
			(start -0.7874 0.4064)
			(end -0.7874 -0.4064)
			(stroke
				(width 0.1524)
				(type default)
			)
			(layer "F.SilkS")
		)
		(fp_line
			(start 0.7874 0.4064)
			(end -0.7874 0.4064)
			(stroke
				(width 0.1524)
				(type default)
			)
			(layer "F.SilkS")
		)
		(fp_line
			(start -0.7874 -0.4064)
			(end 0.7874 -0.4064)
			(stroke
				(width 0.1524)
				(type default)
			)
			(layer "F.SilkS")
		)
		(fp_line
			(start 0.7874 -0.4064)
			(end 0.7874 0.4064)
			(stroke
				(width 0.1524)
				(type default)
			)
			(layer "F.SilkS")
		)
		(fp_line
			(start -0.67945 0.3048)
			(end -0.67945 -0.305054)
			(stroke
				(width 0.1)
				(type default)
			)
			(layer "F.Fab")
		)
		(fp_line
			(start -0.12065 0.3048)
			(end -0.67945 0.3048)
			(stroke
				(width 0.1)
				(type default)
			)
			(layer "F.Fab")
		)
		(fp_line
			(start 0.120396 0.3048)
			(end 0.120396 0.2794)
			(stroke
				(width 0.1)
				(type default)
			)
			(layer "F.Fab")
		)
		(fp_line
			(start 0.67945 0.3048)
			(end 0.120396 0.3048)
			(stroke
				(width 0.1)
				(type default)
			)
			(layer "F.Fab")
		)
		(fp_line
			(start -0.12065 0.2794)
			(end -0.12065 0.3048)
			(stroke
				(width 0.1)
				(type default)
			)
			(layer "F.Fab")
		)
		(fp_line
			(start 0.120396 0.2794)
			(end -0.12065 0.2794)
			(stroke
				(width 0.1)
				(type default)
			)
			(layer "F.Fab")
		)
		(fp_line
			(start -0.12065 -0.2794)
			(end 0.12065 -0.2794)
			(stroke
				(width 0.1)
				(type default)
			)
			(layer "F.Fab")
		)
		(fp_line
			(start 0.12065 -0.2794)
			(end 0.12065 -0.3048)
			(stroke
				(width 0.1)
				(type default)
			)
			(layer "F.Fab")
		)
		(fp_line
			(start 0.12065 -0.3048)
			(end 0.67945 -0.3048)
			(stroke
				(width 0.1)
				(type default)
			)
			(layer "F.Fab")
		)
		(fp_line
			(start 0.67945 -0.3048)
			(end 0.67945 0.3048)
			(stroke
				(width 0.1)
				(type default)
			)
			(layer "F.Fab")
		)
		(fp_line
			(start -0.67945 -0.305054)
			(end -0.12065 -0.305054)
			(stroke
				(width 0.1)
				(type default)
			)
			(layer "F.Fab")
		)
		(fp_line
			(start -0.12065 -0.305054)
			(end -0.12065 -0.2794)
			(stroke
				(width 0.1)
				(type default)
			)
			(layer "F.Fab")
		)
		(pad "1" smd circle
			(at -0.40005 0 270)
			(size 0 0)
			(layers "F.Cu" "F.Mask" "F.Paste")
			(net "P3V3_AUX")
		)
		(pad "2" smd circle
			(at 0.40005 0 270)
			(size 0 0)
			(layers "F.Cu" "F.Mask" "F.Paste")
			(net "GND")
		)
	)
	(footprint ""
		(layer "F.Cu")
		(at 356.349808 -157.812994)
		(property "Reference" "R957"
			(at 0 0 0)
			(layer "F.SilkS")
			(hide yes)
			(effects
				(font
					(size 1.27 1.27)
				)
			)
		)
		(property "Value" ""
			(at 0 0 0)
			(layer "F.Fab")
			(effects
				(font
					(size 1.27 1.27)
				)
			)
		)
		(duplicate_pad_numbers_are_jumpers no)
		(fp_line
			(start -0.7874 -0.4064)
			(end 0.7874 -0.4064)
			(stroke
				(width 0.1524)
				(type default)
			)
			(layer "F.SilkS")
		)
		(fp_line
			(start -0.7874 0.4064)
			(end -0.7874 -0.4064)
			(stroke
				(width 0.1524)
				(type default)
			)
			(layer "F.SilkS")
		)
		(fp_line
			(start 0.7874 -0.4064)
			(end 0.7874 0.4064)
			(stroke
				(width 0.1524)
				(type default)
			)
			(layer "F.SilkS")
		)
		(fp_line
			(start 0.7874 0.4064)
			(end -0.7874 0.4064)
			(stroke
				(width 0.1524)
				(type default)
			)
			(layer "F.SilkS")
		)
		(fp_line
			(start -0.67945 -0.305054)
			(end -0.12065 -0.305054)
			(stroke
				(width 0.1)
				(type default)
			)
			(layer "F.Fab")
		)
		(fp_line
			(start -0.67945 0.3048)
			(end -0.67945 -0.305054)
			(stroke
				(width 0.1)
				(type default)
			)
			(layer "F.Fab")
		)
		(fp_line
			(start -0.12065 -0.305054)
			(end -0.12065 -0.2794)
			(stroke
				(width 0.1)
				(type default)
			)
			(layer "F.Fab")
		)
		(fp_line
			(start -0.12065 -0.2794)
			(end 0.12065 -0.2794)
			(stroke
				(width 0.1)
				(type default)
			)
			(layer "F.Fab")
		)
		(fp_line
			(start -0.12065 0.2794)
			(end -0.12065 0.3048)
			(stroke
				(width 0.1)
				(type default)
			)
			(layer "F.Fab")
		)
		(fp_line
			(start -0.12065 0.3048)
			(end -0.67945 0.3048)
			(stroke
				(width 0.1)
				(type default)
			)
			(layer "F.Fab")
		)
		(fp_line
			(start 0.120396 0.2794)
			(end -0.12065 0.2794)
			(stroke
				(width 0.1)
				(type default)
			)
			(layer "F.Fab")
		)
		(fp_line
			(start 0.120396 0.3048)
			(end 0.120396 0.2794)
			(stroke
				(width 0.1)
				(type default)
			)
			(layer "F.Fab")
		)
		(fp_line
			(start 0.12065 -0.3048)
			(end 0.67945 -0.3048)
			(stroke
				(width 0.1)
				(type default)
			)
			(layer "F.Fab")
		)
		(fp_line
			(start 0.12065 -0.2794)
			(end 0.12065 -0.3048)
			(stroke
				(width 0.1)
				(type default)
			)
			(layer "F.Fab")
		)
		(fp_line
			(start 0.67945 -0.3048)
			(end 0.67945 0.3048)
			(stroke
				(width 0.1)
				(type default)
			)
			(layer "F.Fab")
		)
		(fp_line
			(start 0.67945 0.3048)
			(end 0.120396 0.3048)
			(stroke
				(width 0.1)
				(type default)
			)
			(layer "F.Fab")
		)
		(pad "1" smd circle
			(at -0.40005 0)
			(size 0 0)
			(layers "F.Cu" "F.Mask" "F.Paste")
			(net "P3V3_AUX")
		)
		(pad "2" smd circle
			(at 0.40005 0)
			(size 0 0)
			(layers "F.Cu" "F.Mask" "F.Paste")
			(net "PWRGD_P12V_NIC6_CO")
		)
	)
	(footprint ""
		(layer "F.Cu")
		(at 45.246798 -37.47516)
		(property "Reference" "R5886"
			(at 0 0 0)
			(layer "F.SilkS")
			(hide yes)
			(effects
				(font
					(size 1.27 1.27)
				)
			)
		)
		(property "Value" ""
			(at 0 0 0)
			(layer "F.Fab")
			(effects
				(font
					(size 1.27 1.27)
				)
			)
		)
		(duplicate_pad_numbers_are_jumpers no)
		(fp_line
			(start -0.7874 -0.4064)
			(end 0.7874 -0.4064)
			(stroke
				(width 0.1524)
				(type default)
			)
			(layer "F.SilkS")
		)
		(fp_line
			(start -0.7874 0.4064)
			(end -0.7874 -0.4064)
			(stroke
				(width 0.1524)
				(type default)
			)
			(layer "F.SilkS")
		)
		(fp_line
			(start 0.7874 -0.4064)
			(end 0.7874 0.4064)
			(stroke
				(width 0.1524)
				(type default)
			)
			(layer "F.SilkS")
		)
		(fp_line
			(start 0.7874 0.4064)
			(end -0.7874 0.4064)
			(stroke
				(width 0.1524)
				(type default)
			)
			(layer "F.SilkS")
		)
		(fp_line
			(start -0.67945 -0.305054)
			(end -0.12065 -0.305054)
			(stroke
				(width 0.1)
				(type default)
			)
			(layer "F.Fab")
		)
		(fp_line
			(start -0.67945 0.3048)
			(end -0.67945 -0.305054)
			(stroke
				(width 0.1)
				(type default)
			)
			(layer "F.Fab")
		)
		(fp_line
			(start -0.12065 -0.305054)
			(end -0.12065 -0.2794)
			(stroke
				(width 0.1)
				(type default)
			)
			(layer "F.Fab")
		)
		(fp_line
			(start -0.12065 -0.2794)
			(end 0.12065 -0.2794)
			(stroke
				(width 0.1)
				(type default)
			)
			(layer "F.Fab")
		)
		(fp_line
			(start -0.12065 0.2794)
			(end -0.12065 0.3048)
			(stroke
				(width 0.1)
				(type default)
			)
			(layer "F.Fab")
		)
		(fp_line
			(start -0.12065 0.3048)
			(end -0.67945 0.3048)
			(stroke
				(width 0.1)
				(type default)
			)
			(layer "F.Fab")
		)
		(fp_line
			(start 0.120396 0.2794)
			(end -0.12065 0.2794)
			(stroke
				(width 0.1)
				(type default)
			)
			(layer "F.Fab")
		)
		(fp_line
			(start 0.120396 0.3048)
			(end 0.120396 0.2794)
			(stroke
				(width 0.1)
				(type default)
			)
			(layer "F.Fab")
		)
		(fp_line
			(start 0.12065 -0.3048)
			(end 0.67945 -0.3048)
			(stroke
				(width 0.1)
				(type default)
			)
			(layer "F.Fab")
		)
		(fp_line
			(start 0.12065 -0.2794)
			(end 0.12065 -0.3048)
			(stroke
				(width 0.1)
				(type default)
			)
			(layer "F.Fab")
		)
		(fp_line
			(start 0.67945 -0.3048)
			(end 0.67945 0.3048)
			(stroke
				(width 0.1)
				(type default)
			)
			(layer "F.Fab")
		)
		(fp_line
			(start 0.67945 0.3048)
			(end 0.120396 0.3048)
			(stroke
				(width 0.1)
				(type default)
			)
			(layer "F.Fab")
		)
		(pad "1" smd circle
			(at -0.40005 0)
			(size 0 0)
			(layers "F.Cu" "F.Mask" "F.Paste")
			(net "P3V3_SSD2")
		)
		(pad "2" smd circle
			(at 0.40005 0)
			(size 0 0)
			(layers "F.Cu" "F.Mask" "F.Paste")
			(net "P3V3_SSD2_PG_G1")
		)
	)
	(footprint ""
		(layer "F.Cu")
		(at 411.530292 -197.556882)
		(property "Reference" "Q233"
			(at -3.08991 1.494282 0)
			(unlocked yes)
			(layer "F.SilkS")
			(effects
				(font
					(size 0.7874 0.5842)
					(thickness 0.1524)
				)
			)
		)
		(property "Value" ""
			(at 0 0 0)
			(layer "F.Fab")
			(effects
				(font
					(size 1.27 1.27)
				)
			)
		)
		(duplicate_pad_numbers_are_jumpers no)
		(fp_line
			(start -1.376172 -1.199896)
			(end -0.508 -1.199896)
			(stroke
				(width 0.1524)
				(type default)
			)
			(layer "F.SilkS")
		)
		(fp_line
			(start -1.376172 1.199896)
			(end -1.376172 -1.199896)
			(stroke
				(width 0.1524)
				(type default)
			)
			(layer "F.SilkS")
		)
		(fp_line
			(start -0.508 -1.199896)
			(end 0 -0.762)
			(stroke
				(width 0.1524)
				(type default)
			)
			(layer "F.SilkS")
		)
		(fp_line
			(start 0 -0.762)
			(end 0.508 -1.199896)
			(stroke
				(width 0.1524)
				(type default)
			)
			(layer "F.SilkS")
		)
		(fp_line
			(start 0.508 -1.199896)
			(end 1.376172 -1.199896)
			(stroke
				(width 0.1524)
				(type default)
			)
			(layer "F.SilkS")
		)
		(fp_line
			(start 1.376172 -1.199896)
			(end 1.376172 1.199896)
			(stroke
				(width 0.1524)
				(type default)
			)
			(layer "F.SilkS")
		)
		(fp_line
			(start 1.376172 1.199896)
			(end -1.376172 1.199896)
			(stroke
				(width 0.1524)
				(type default)
			)
			(layer "F.SilkS")
		)
		(fp_poly
			(pts
				(xy -1.4605 -0.7493) (xy -2.2225 -1.1303) (xy -2.2225 -0.3683)
			)
			(stroke
				(width 0)
				(type default)
			)
			(fill yes)
			(layer "F.SilkS")
		)
		(fp_line
			(start -0.674878 -1.100074)
			(end 0.674878 -1.100074)
			(stroke
				(width 0.1)
				(type default)
			)
			(layer "F.Fab")
		)
		(fp_line
			(start -0.674878 1.100074)
			(end -0.674878 -1.100074)
			(stroke
				(width 0.1)
				(type default)
			)
			(layer "F.Fab")
		)
		(fp_line
			(start 0.674878 -1.100074)
			(end 0.674878 1.100074)
			(stroke
				(width 0.1)
				(type default)
			)
			(layer "F.Fab")
		)
		(fp_line
			(start 0.674878 1.100074)
			(end -0.674878 1.100074)
			(stroke
				(width 0.1)
				(type default)
			)
			(layer "F.Fab")
		)
		(fp_poly
			(pts
				(xy -1.4605 -0.7493) (xy -2.2225 -1.1303) (xy -2.2225 -0.3683)
			)
			(stroke
				(width 0)
				(type default)
			)
			(fill yes)
			(layer "F.Fab")
		)
		(pad "1" smd rect
			(at -0.899922 -0.750062 270)
			(size 0.6096 0.6096)
			(layers "F.Cu" "F.Mask" "F.Paste")
			(net "GND")
		)
		(pad "2" smd rect
			(at -0.899922 0 270)
			(size 0.4064 0.6096)
			(layers "F.Cu" "F.Mask" "F.Paste")
			(net "FPGA_PEX0_MODE_SEL1_R")
		)
		(pad "3" smd rect
			(at -0.899922 0.750062 270)
			(size 0.6096 0.6096)
			(layers "F.Cu" "F.Mask" "F.Paste")
			(net "FPGA_PEX0_MODE_SEL1_ISO")
		)
		(pad "4" smd rect
			(at 0.899922 0.750062 270)
			(size 0.6096 0.6096)
			(layers "F.Cu" "F.Mask" "F.Paste")
			(net "GND")
		)
		(pad "5" smd rect
			(at 0.899922 0 270)
			(size 0.4064 0.6096)
			(layers "F.Cu" "F.Mask" "F.Paste")
			(net "FPGA_PEX0_MODE_SEL1_D_N")
		)
		(pad "6" smd rect
			(at 0.899922 -0.750062 270)
			(size 0.6096 0.6096)
			(layers "F.Cu" "F.Mask" "F.Paste")
			(net "FPGA_PEX0_MODE_SEL1_D_N")
		)
	)
	(footprint ""
		(layer "F.Cu")
		(at 268.445742 -261.663434)
		(property "Reference" "C3387"
			(at 0 0 0)
			(layer "F.SilkS")
			(hide yes)
			(effects
				(font
					(size 1.27 1.27)
				)
			)
		)
		(property "Value" ""
			(at 0 0 0)
			(layer "F.Fab")
			(effects
				(font
					(size 1.27 1.27)
				)
			)
		)
		(duplicate_pad_numbers_are_jumpers no)
		(fp_line
			(start -1.2954 -0.5842)
			(end 1.2954 -0.5842)
			(stroke
				(width 0.1524)
				(type default)
			)
			(layer "F.SilkS")
		)
		(fp_line
			(start -1.2954 0.5842)
			(end -1.2954 -0.5842)
			(stroke
				(width 0.1524)
				(type default)
			)
			(layer "F.SilkS")
		)
		(fp_line
			(start 1.2954 -0.5842)
			(end 1.2954 0.5842)
			(stroke
				(width 0.1524)
				(type default)
			)
			(layer "F.SilkS")
		)
		(fp_line
			(start 1.2954 0.5842)
			(end -1.2954 0.5842)
			(stroke
				(width 0.1524)
				(type default)
			)
			(layer "F.SilkS")
		)
		(fp_line
			(start -1.1938 -0.4064)
			(end -0.8636 -0.4064)
			(stroke
				(width 0.1)
				(type default)
			)
			(layer "F.Fab")
		)
		(fp_line
			(start -1.1938 0.4064)
			(end -1.1938 -0.4064)
			(stroke
				(width 0.1)
				(type default)
			)
			(layer "F.Fab")
		)
		(fp_line
			(start -0.8636 -0.4572)
			(end 0.8636 -0.4572)
			(stroke
				(width 0.1)
				(type default)
			)
			(layer "F.Fab")
		)
		(fp_line
			(start -0.8636 -0.4064)
			(end -0.8636 -0.4572)
			(stroke
				(width 0.1)
				(type default)
			)
			(layer "F.Fab")
		)
		(fp_line
			(start -0.8636 0.4064)
			(end -1.1938 0.4064)
			(stroke
				(width 0.1)
				(type default)
			)
			(layer "F.Fab")
		)
		(fp_line
			(start -0.8636 0.4572)
			(end -0.8636 0.4064)
			(stroke
				(width 0.1)
				(type default)
			)
			(layer "F.Fab")
		)
		(fp_line
			(start 0.8636 -0.4572)
			(end 0.8636 -0.4064)
			(stroke
				(width 0.1)
				(type default)
			)
			(layer "F.Fab")
		)
		(fp_line
			(start 0.8636 -0.4064)
			(end 1.1938 -0.4064)
			(stroke
				(width 0.1)
				(type default)
			)
			(layer "F.Fab")
		)
		(fp_line
			(start 0.8636 0.4064)
			(end 0.8636 0.4572)
			(stroke
				(width 0.1)
				(type default)
			)
			(layer "F.Fab")
		)
		(fp_line
			(start 0.8636 0.4572)
			(end -0.8636 0.4572)
			(stroke
				(width 0.1)
				(type default)
			)
			(layer "F.Fab")
		)
		(fp_line
			(start 1.1938 -0.4064)
			(end 1.1938 0.4064)
			(stroke
				(width 0.1)
				(type default)
			)
			(layer "F.Fab")
		)
		(fp_line
			(start 1.1938 0.4064)
			(end 0.8636 0.4064)
			(stroke
				(width 0.1)
				(type default)
			)
			(layer "F.Fab")
		)
		(pad "1" smd rect
			(at -0.7366 0 270)
			(size 0.7112 0.8128)
			(layers "F.Cu" "F.Mask" "F.Paste")
			(net "PCEPLL3_VDDA18_PEX2")
		)
		(pad "2" smd rect
			(at 0.7366 0 270)
			(size 0.7112 0.8128)
			(layers "F.Cu" "F.Mask" "F.Paste")
			(net "GND")
		)
	)
	(footprint ""
		(layer "F.Cu")
		(at 497.694712 -546.502082 180)
		(property "Reference" "SCREW_6"
			(at -3.2385 -1.402334 0)
			(unlocked yes)
			(layer "B.SilkS")
			(effects
				(font
					(size 0.7874 0.5842)
					(thickness 0.1524)
				)
				(justify mirror)
			)
		)
		(property "Value" ""
			(at 0 0 180)
			(layer "F.Fab")
			(effects
				(font
					(size 1.27 1.27)
				)
			)
		)
		(duplicate_pad_numbers_are_jumpers no)
		(pad "1" thru_hole circle
			(at 0 0 180)
			(size 0.4572 0.4572)
			(drill 0.2032)
			(layers "*.Cu" "*.Mask")
			(remove_unused_layers no)
			(net "Net_9158")
			(clearance 0.127)
			(thermal_gap 0.127)
			(padstack
				(mode front_inner_back)
				(layer "Inner"
					(shape circle)
					(size 0.4572 0.4572)
					(clearance 0.127)
				)
				(layer "B.Cu"
					(shape circle)
					(size 0.508 0.508)
					(clearance 0.1016)
				)
			)
		)
	)
)
